(kicad_pcb
	(version 20260206)
	(generator "pcbnew")
	(generator_version "10.0")
	(general
		(thickness 1.6)
		(legacy_teardrops no)
	)
	(paper "A4")
	(title_block
		(title "panther-plus-userver — 13130-1b_20150205.brd")
		(comment 1 "Honey Badger (Wiwynn) / footprint 1214 of 1509 (DIMM3), pads 93-99 of 210")
	)
	(layers
		(0 "F.Cu" signal "TOP")
		(4 "In1.Cu" signal "L2")
		(6 "In2.Cu" signal "L3")
		(8 "In3.Cu" signal "L4")
		(10 "In4.Cu" signal "L5")
		(12 "In5.Cu" signal "L6")
		(14 "In6.Cu" signal "L7")
		(16 "In7.Cu" signal "L8")
		(18 "In8.Cu" signal "L9")
		(20 "In9.Cu" signal "L10")
		(22 "In10.Cu" signal "L11")
		(2 "B.Cu" signal "BOTTOM")
		(9 "F.Adhes" user "F.Adhesive")
		(11 "B.Adhes" user "B.Adhesive")
		(13 "F.Paste" user "Package Geometry/Pastemask Top")
		(15 "B.Paste" user "Package Geometry/Pastemask Bottom")
		(5 "F.SilkS" user "Ref Des/Silkscreen Top")
		(7 "B.SilkS" user "Ref Des/Silkscreen Bottom")
		(1 "F.Mask" user "Board Geometry/Soldermask Top")
		(3 "B.Mask" user "Board Geometry/Soldermask Bottom")
		(17 "Dwgs.User" user "User.Drawings")
		(19 "Cmts.User" user "User.Comments")
		(21 "Eco1.User" user "User.Eco1")
		(23 "Eco2.User" user "User.Eco2")
		(25 "Edge.Cuts" user "Board Geometry/Outline")
		(27 "Margin" user)
		(31 "F.CrtYd" user "Package Geometry/Place Bound Top")
		(29 "B.CrtYd" user "Package Geometry/Place Bound Bottom")
		(35 "F.Fab" user "Ref Des/Assembly Top")
		(33 "B.Fab" user "Ref Des/Assembly Bottom")
	)
	(footprint ""
		(layer "B.Cu")
		(at 159.999934 -5.790692)
		(property "Reference" "DIMM3"
			(at 0 0 0)
			(layer "B.SilkS")
			(hide yes)
			(effects
				(font
					(size 1.27 1.27)
				)
				(justify mirror)
			)
		)
		(property "Value" "DDR3-204P-142-COLAY-1-GP-U"
			(at 41.312338 -16.676878 0)
			(unlocked yes)
			(layer "B.Fab")
			(hide yes)
			(effects
				(font
					(size 1.016 1.016)
					(thickness 0.1524)
				)
				(justify mirror)
			)
		)
		(property "Device Type" "AS0A626-J8R6-7H-COLAY-1"
			(at 41.312338 -18.200878 0)
			(unlocked yes)
			(layer "B.Fab")
			(hide yes)
			(effects
				(font
					(size 1.016 1.016)
					(thickness 0.1524)
				)
				(justify mirror)
			)
		)
		(duplicate_pad_numbers_are_jumpers no)
		(pad "91" smd custom
			(at -2.249932 -4.100068 180)
			(size 0.1143 0.1143)
			(layers "B.Cu" "B.Mask" "B.Paste")
			(net "M_B_BS2")
			(options
				(clearance outline)
				(anchor circle)
			)
			(primitives
				(gr_poly
					(pts
						(xy 0 -0.9017) (xy -0.03175 -0.89916) (xy -0.0635 -0.889) (xy -0.09144 -0.87376) (xy -0.11684 -0.85344)
						(xy -0.13716 -0.82804) (xy -0.1524 -0.8001) (xy -0.16256 -0.76835) (xy -0.1651 -0.7366) (xy -0.1651 -0.19685)
						(xy -0.17272 -0.18923) (xy -0.17907 -0.18034) (xy -0.18669 -0.17145) (xy -0.19177 -0.16256) (xy -0.19812 -0.15367)
						(xy -0.20828 -0.13335) (xy -0.21971 -0.10287) (xy -0.22225 -0.09271) (xy -0.22479 -0.08128) (xy -0.22606 -0.07112)
						(xy -0.2286 -0.05969) (xy -0.2286 -0.01651) (xy -0.22606 -0.00508) (xy -0.22479 0.00508) (xy -0.22225 0.01651)
						(xy -0.21971 0.02667) (xy -0.20828 0.05715) (xy -0.19812 0.07747) (xy -0.19177 0.08636) (xy -0.18669 0.09525)
						(xy -0.17907 0.10414) (xy -0.17272 0.11303) (xy -0.1651 0.12065) (xy -0.1651 0.7366) (xy -0.16256 0.76835)
						(xy -0.1524 0.8001) (xy -0.13716 0.82804) (xy -0.11684 0.85344) (xy -0.09144 0.87376) (xy -0.0635 0.889)
						(xy -0.03175 0.89916) (xy 0 0.9017) (xy 0.03175 0.89916) (xy 0.0635 0.889) (xy 0.09144 0.87376)
						(xy 0.11684 0.85344) (xy 0.13716 0.82804) (xy 0.1524 0.8001) (xy 0.16256 0.76835) (xy 0.1651 0.7366)
						(xy 0.1651 0.11938) (xy 0.17272 0.11176) (xy 0.19812 0.0762) (xy 0.2032 0.06604) (xy 0.20701 0.05715)
						(xy 0.21209 0.04699) (xy 0.2159 0.03683) (xy 0.21844 0.02667) (xy 0.22225 0.01524) (xy 0.22352 0.00508)
						(xy 0.22606 -0.00508) (xy 0.22733 -0.01651) (xy 0.22733 -0.02667) (xy 0.2286 -0.0381) (xy 0.22733 -0.04953)
						(xy 0.22733 -0.05969) (xy 0.22606 -0.07112) (xy 0.22352 -0.08128) (xy 0.22225 -0.09144) (xy 0.21844 -0.10287)
						(xy 0.2159 -0.11303) (xy 0.21209 -0.12319) (xy 0.20701 -0.13335) (xy 0.2032 -0.14224) (xy 0.19812 -0.1524)
						(xy 0.17272 -0.18796) (xy 0.1651 -0.19558) (xy 0.1651 -0.7366) (xy 0.16256 -0.76835) (xy 0.1524 -0.8001)
						(xy 0.13716 -0.82804) (xy 0.11684 -0.85344) (xy 0.09144 -0.87376) (xy 0.0635 -0.889) (xy 0.03175 -0.89916)
					)
					(width 0)
					(fill yes)
				)
			)
		)
		(pad "92" smd custom
			(at -1.949958 4.100068 180)
			(size 0.1143 0.1143)
			(layers "B.Cu" "B.Mask" "B.Paste")
			(net "M_B_MA9")
			(options
				(clearance outline)
				(anchor circle)
			)
			(primitives
				(gr_poly
					(pts
						(xy 0 -0.9017) (xy -0.03175 -0.89916) (xy -0.0635 -0.889) (xy -0.09144 -0.87376) (xy -0.11684 -0.85344)
						(xy -0.13716 -0.82804) (xy -0.1524 -0.8001) (xy -0.16256 -0.76835) (xy -0.1651 -0.7366) (xy -0.1651 -0.11938)
						(xy -0.17272 -0.11176) (xy -0.19812 -0.0762) (xy -0.2032 -0.06604) (xy -0.20701 -0.05715) (xy -0.21209 -0.04699)
						(xy -0.2159 -0.03683) (xy -0.21844 -0.02667) (xy -0.22225 -0.01524) (xy -0.22352 -0.00508) (xy -0.22606 0.00508)
						(xy -0.22733 0.01651) (xy -0.22733 0.02667) (xy -0.2286 0.0381) (xy -0.22733 0.04953) (xy -0.22733 0.05969)
						(xy -0.22606 0.07112) (xy -0.22352 0.08128) (xy -0.22225 0.09144) (xy -0.21844 0.10287) (xy -0.2159 0.11303)
						(xy -0.21209 0.12319) (xy -0.20701 0.13335) (xy -0.2032 0.14224) (xy -0.19812 0.1524) (xy -0.17272 0.18796)
						(xy -0.1651 0.19558) (xy -0.1651 0.7366) (xy -0.16256 0.76835) (xy -0.1524 0.8001) (xy -0.13716 0.82804)
						(xy -0.11684 0.85344) (xy -0.09144 0.87376) (xy -0.0635 0.889) (xy -0.03175 0.89916) (xy 0 0.9017)
						(xy 0.03175 0.89916) (xy 0.0635 0.889) (xy 0.09144 0.87376) (xy 0.11684 0.85344) (xy 0.13716 0.82804)
						(xy 0.1524 0.8001) (xy 0.16256 0.76835) (xy 0.1651 0.7366) (xy 0.1651 0.19685) (xy 0.17272 0.18923)
						(xy 0.17907 0.18034) (xy 0.18669 0.17145) (xy 0.19177 0.16256) (xy 0.19812 0.15367) (xy 0.20828 0.13335)
						(xy 0.21971 0.10287) (xy 0.22225 0.09271) (xy 0.22479 0.08128) (xy 0.22606 0.07112) (xy 0.2286 0.05969)
						(xy 0.2286 0.01651) (xy 0.22606 0.00508) (xy 0.22479 -0.00508) (xy 0.22225 -0.01651) (xy 0.21971 -0.02667)
						(xy 0.20828 -0.05715) (xy 0.19812 -0.07747) (xy 0.19177 -0.08636) (xy 0.18669 -0.09525) (xy 0.17907 -0.10414)
						(xy 0.17272 -0.11303) (xy 0.1651 -0.12065) (xy 0.1651 -0.7366) (xy 0.16256 -0.76835) (xy 0.1524 -0.8001)
						(xy 0.13716 -0.82804) (xy 0.11684 -0.85344) (xy 0.09144 -0.87376) (xy 0.0635 -0.889) (xy 0.03175 -0.89916)
					)
					(width 0)
					(fill yes)
				)
			)
		)
		(pad "93" smd custom
			(at -1.649984 -4.100068 180)
			(size 0.1143 0.1143)
			(layers "B.Cu" "B.Mask" "B.Paste")
			(net "PV_VDDR")
			(options
				(clearance outline)
				(anchor circle)
			)
			(primitives
				(gr_poly
					(pts
						(xy 0 -0.9017) (xy -0.03175 -0.89916) (xy -0.0635 -0.889) (xy -0.09144 -0.87376) (xy -0.11684 -0.85344)
						(xy -0.13716 -0.82804) (xy -0.1524 -0.8001) (xy -0.16256 -0.76835) (xy -0.1651 -0.7366) (xy -0.1651 -0.44958)
						(xy -0.17272 -0.44196) (xy -0.19812 -0.4064) (xy -0.2032 -0.39624) (xy -0.20701 -0.38735) (xy -0.21209 -0.37719)
						(xy -0.2159 -0.36703) (xy -0.21844 -0.35687) (xy -0.22225 -0.34544) (xy -0.22352 -0.33528) (xy -0.22606 -0.32512)
						(xy -0.22733 -0.31369) (xy -0.22733 -0.30353) (xy -0.2286 -0.2921) (xy -0.22733 -0.28067) (xy -0.22733 -0.27051)
						(xy -0.22606 -0.25908) (xy -0.22352 -0.24892) (xy -0.22225 -0.23876) (xy -0.21844 -0.22733) (xy -0.2159 -0.21717)
						(xy -0.21209 -0.20701) (xy -0.20701 -0.19685) (xy -0.2032 -0.18796) (xy -0.19812 -0.1778) (xy -0.17272 -0.14224)
						(xy -0.1651 -0.13462) (xy -0.1651 0.7366) (xy -0.16256 0.76835) (xy -0.1524 0.8001) (xy -0.13716 0.82804)
						(xy -0.11684 0.85344) (xy -0.09144 0.87376) (xy -0.0635 0.889) (xy -0.03175 0.89916) (xy 0 0.9017)
						(xy 0.03175 0.89916) (xy 0.0635 0.889) (xy 0.09144 0.87376) (xy 0.11684 0.85344) (xy 0.13716 0.82804)
						(xy 0.1524 0.8001) (xy 0.16256 0.76835) (xy 0.1651 0.7366) (xy 0.1651 -0.13462) (xy 0.17272 -0.14224)
						(xy 0.19812 -0.1778) (xy 0.2032 -0.18796) (xy 0.20701 -0.19685) (xy 0.21209 -0.20701) (xy 0.2159 -0.21717)
						(xy 0.21844 -0.22733) (xy 0.22225 -0.23876) (xy 0.22352 -0.24892) (xy 0.22606 -0.25908) (xy 0.22733 -0.27051)
						(xy 0.22733 -0.28067) (xy 0.2286 -0.2921) (xy 0.22733 -0.30353) (xy 0.22733 -0.31369) (xy 0.22606 -0.32512)
						(xy 0.22352 -0.33528) (xy 0.22225 -0.34544) (xy 0.21844 -0.35687) (xy 0.2159 -0.36703) (xy 0.21209 -0.37719)
						(xy 0.20701 -0.38735) (xy 0.2032 -0.39624) (xy 0.19812 -0.4064) (xy 0.17272 -0.44196) (xy 0.1651 -0.44958)
						(xy 0.1651 -0.7366) (xy 0.16256 -0.76835) (xy 0.1524 -0.8001) (xy 0.13716 -0.82804) (xy 0.11684 -0.85344)
						(xy 0.09144 -0.87376) (xy 0.0635 -0.889) (xy 0.03175 -0.89916)
					)
					(width 0)
					(fill yes)
				)
			)
		)
		(pad "94" smd custom
			(at -1.35001 4.100068 180)
			(size 0.1143 0.1143)
			(layers "B.Cu" "B.Mask" "B.Paste")
			(net "PV_VDDR")
			(options
				(clearance outline)
				(anchor circle)
			)
			(primitives
				(gr_poly
					(pts
						(xy 0 -0.9017) (xy -0.03175 -0.89916) (xy -0.0635 -0.889) (xy -0.09144 -0.87376) (xy -0.11684 -0.85344)
						(xy -0.13716 -0.82804) (xy -0.1524 -0.8001) (xy -0.16256 -0.76835) (xy -0.1651 -0.7366) (xy -0.1651 0.13462)
						(xy -0.17272 0.14224) (xy -0.19812 0.1778) (xy -0.2032 0.18796) (xy -0.20701 0.19685) (xy -0.21209 0.20701)
						(xy -0.2159 0.21717) (xy -0.21844 0.22733) (xy -0.22225 0.23876) (xy -0.22352 0.24892) (xy -0.22606 0.25908)
						(xy -0.22733 0.27051) (xy -0.22733 0.28067) (xy -0.2286 0.2921) (xy -0.22733 0.30353) (xy -0.22733 0.31369)
						(xy -0.22606 0.32512) (xy -0.22352 0.33528) (xy -0.22225 0.34544) (xy -0.21844 0.35687) (xy -0.2159 0.36703)
						(xy -0.21209 0.37719) (xy -0.20701 0.38735) (xy -0.2032 0.39624) (xy -0.19812 0.4064) (xy -0.17272 0.44196)
						(xy -0.1651 0.44958) (xy -0.1651 0.7366) (xy -0.16256 0.76835) (xy -0.1524 0.8001) (xy -0.13716 0.82804)
						(xy -0.11684 0.85344) (xy -0.09144 0.87376) (xy -0.0635 0.889) (xy -0.03175 0.89916) (xy 0 0.9017)
						(xy 0.03175 0.89916) (xy 0.0635 0.889) (xy 0.09144 0.87376) (xy 0.11684 0.85344) (xy 0.13716 0.82804)
						(xy 0.1524 0.8001) (xy 0.16256 0.76835) (xy 0.1651 0.7366) (xy 0.1651 0.44958) (xy 0.17272 0.44196)
						(xy 0.19812 0.4064) (xy 0.2032 0.39624) (xy 0.20701 0.38735) (xy 0.21209 0.37719) (xy 0.2159 0.36703)
						(xy 0.21844 0.35687) (xy 0.22225 0.34544) (xy 0.22352 0.33528) (xy 0.22606 0.32512) (xy 0.22733 0.31369)
						(xy 0.22733 0.30353) (xy 0.2286 0.2921) (xy 0.22733 0.28067) (xy 0.22733 0.27051) (xy 0.22606 0.25908)
						(xy 0.22352 0.24892) (xy 0.22225 0.23876) (xy 0.21844 0.22733) (xy 0.2159 0.21717) (xy 0.21209 0.20701)
						(xy 0.20701 0.19685) (xy 0.2032 0.18796) (xy 0.19812 0.1778) (xy 0.17272 0.14224) (xy 0.1651 0.13462)
						(xy 0.1651 -0.7366) (xy 0.16256 -0.76835) (xy 0.1524 -0.8001) (xy 0.13716 -0.82804) (xy 0.11684 -0.85344)
						(xy 0.09144 -0.87376) (xy 0.0635 -0.889) (xy 0.03175 -0.89916)
					)
					(width 0)
					(fill yes)
				)
			)
		)
		(pad "95" smd custom
			(at -1.050036 -4.100068 180)
			(size 0.1143 0.1143)
			(layers "B.Cu" "B.Mask" "B.Paste")
			(net "M_B_MA12")
			(options
				(clearance outline)
				(anchor circle)
			)
			(primitives
				(gr_poly
					(pts
						(xy 0 -0.9017) (xy -0.03175 -0.89916) (xy -0.0635 -0.889) (xy -0.09144 -0.87376) (xy -0.11684 -0.85344)
						(xy -0.13716 -0.82804) (xy -0.1524 -0.8001) (xy -0.16256 -0.76835) (xy -0.1651 -0.7366) (xy -0.1651 -0.19685)
						(xy -0.17272 -0.18923) (xy -0.17907 -0.18034) (xy -0.18669 -0.17145) (xy -0.19177 -0.16256) (xy -0.19812 -0.15367)
						(xy -0.20828 -0.13335) (xy -0.21971 -0.10287) (xy -0.22225 -0.09271) (xy -0.22479 -0.08128) (xy -0.22606 -0.07112)
						(xy -0.2286 -0.05969) (xy -0.2286 -0.01651) (xy -0.22606 -0.00508) (xy -0.22479 0.00508) (xy -0.22225 0.01651)
						(xy -0.21971 0.02667) (xy -0.20828 0.05715) (xy -0.19812 0.07747) (xy -0.19177 0.08636) (xy -0.18669 0.09525)
						(xy -0.17907 0.10414) (xy -0.17272 0.11303) (xy -0.1651 0.12065) (xy -0.1651 0.7366) (xy -0.16256 0.76835)
						(xy -0.1524 0.8001) (xy -0.13716 0.82804) (xy -0.11684 0.85344) (xy -0.09144 0.87376) (xy -0.0635 0.889)
						(xy -0.03175 0.89916) (xy 0 0.9017) (xy 0.03175 0.89916) (xy 0.0635 0.889) (xy 0.09144 0.87376)
						(xy 0.11684 0.85344) (xy 0.13716 0.82804) (xy 0.1524 0.8001) (xy 0.16256 0.76835) (xy 0.1651 0.7366)
						(xy 0.1651 0.11938) (xy 0.17272 0.11176) (xy 0.19812 0.0762) (xy 0.2032 0.06604) (xy 0.20701 0.05715)
						(xy 0.21209 0.04699) (xy 0.2159 0.03683) (xy 0.21844 0.02667) (xy 0.22225 0.01524) (xy 0.22352 0.00508)
						(xy 0.22606 -0.00508) (xy 0.22733 -0.01651) (xy 0.22733 -0.02667) (xy 0.2286 -0.0381) (xy 0.22733 -0.04953)
						(xy 0.22733 -0.05969) (xy 0.22606 -0.07112) (xy 0.22352 -0.08128) (xy 0.22225 -0.09144) (xy 0.21844 -0.10287)
						(xy 0.2159 -0.11303) (xy 0.21209 -0.12319) (xy 0.20701 -0.13335) (xy 0.2032 -0.14224) (xy 0.19812 -0.1524)
						(xy 0.17272 -0.18796) (xy 0.1651 -0.19558) (xy 0.1651 -0.7366) (xy 0.16256 -0.76835) (xy 0.1524 -0.8001)
						(xy 0.13716 -0.82804) (xy 0.11684 -0.85344) (xy 0.09144 -0.87376) (xy 0.0635 -0.889) (xy 0.03175 -0.89916)
					)
					(width 0)
					(fill yes)
				)
			)
		)
		(pad "96" smd custom
			(at -0.750062 4.100068 180)
			(size 0.1143 0.1143)
			(layers "B.Cu" "B.Mask" "B.Paste")
			(net "M_B_MA11")
			(options
				(clearance outline)
				(anchor circle)
			)
			(primitives
				(gr_poly
					(pts
						(xy 0 -0.9017) (xy -0.03175 -0.89916) (xy -0.0635 -0.889) (xy -0.09144 -0.87376) (xy -0.11684 -0.85344)
						(xy -0.13716 -0.82804) (xy -0.1524 -0.8001) (xy -0.16256 -0.76835) (xy -0.1651 -0.7366) (xy -0.1651 -0.11938)
						(xy -0.17272 -0.11176) (xy -0.19812 -0.0762) (xy -0.2032 -0.06604) (xy -0.20701 -0.05715) (xy -0.21209 -0.04699)
						(xy -0.2159 -0.03683) (xy -0.21844 -0.02667) (xy -0.22225 -0.01524) (xy -0.22352 -0.00508) (xy -0.22606 0.00508)
						(xy -0.22733 0.01651) (xy -0.22733 0.02667) (xy -0.2286 0.0381) (xy -0.22733 0.04953) (xy -0.22733 0.05969)
						(xy -0.22606 0.07112) (xy -0.22352 0.08128) (xy -0.22225 0.09144) (xy -0.21844 0.10287) (xy -0.2159 0.11303)
						(xy -0.21209 0.12319) (xy -0.20701 0.13335) (xy -0.2032 0.14224) (xy -0.19812 0.1524) (xy -0.17272 0.18796)
						(xy -0.1651 0.19558) (xy -0.1651 0.7366) (xy -0.16256 0.76835) (xy -0.1524 0.8001) (xy -0.13716 0.82804)
						(xy -0.11684 0.85344) (xy -0.09144 0.87376) (xy -0.0635 0.889) (xy -0.03175 0.89916) (xy 0 0.9017)
						(xy 0.03175 0.89916) (xy 0.0635 0.889) (xy 0.09144 0.87376) (xy 0.11684 0.85344) (xy 0.13716 0.82804)
						(xy 0.1524 0.8001) (xy 0.16256 0.76835) (xy 0.1651 0.7366) (xy 0.1651 0.19685) (xy 0.17272 0.18923)
						(xy 0.17907 0.18034) (xy 0.18669 0.17145) (xy 0.19177 0.16256) (xy 0.19812 0.15367) (xy 0.20828 0.13335)
						(xy 0.21971 0.10287) (xy 0.22225 0.09271) (xy 0.22479 0.08128) (xy 0.22606 0.07112) (xy 0.2286 0.05969)
						(xy 0.2286 0.01651) (xy 0.22606 0.00508) (xy 0.22479 -0.00508) (xy 0.22225 -0.01651) (xy 0.21971 -0.02667)
						(xy 0.20828 -0.05715) (xy 0.19812 -0.07747) (xy 0.19177 -0.08636) (xy 0.18669 -0.09525) (xy 0.17907 -0.10414)
						(xy 0.17272 -0.11303) (xy 0.1651 -0.12065) (xy 0.1651 -0.7366) (xy 0.16256 -0.76835) (xy 0.1524 -0.8001)
						(xy 0.13716 -0.82804) (xy 0.11684 -0.85344) (xy 0.09144 -0.87376) (xy 0.0635 -0.889) (xy 0.03175 -0.89916)
					)
					(width 0)
					(fill yes)
				)
			)
		)
		(pad "97" smd custom
			(at -0.450088 -4.100068 180)
			(size 0.1143 0.1143)
			(layers "B.Cu" "B.Mask" "B.Paste")
			(net "M_B_MA8")
			(options
				(clearance outline)
				(anchor circle)
			)
			(primitives
				(gr_poly
					(pts
						(xy 0 -0.9017) (xy -0.03175 -0.89916) (xy -0.0635 -0.889) (xy -0.09144 -0.87376) (xy -0.11684 -0.85344)
						(xy -0.13716 -0.82804) (xy -0.1524 -0.8001) (xy -0.16256 -0.76835) (xy -0.1651 -0.7366) (xy -0.1651 -0.44958)
						(xy -0.17272 -0.44196) (xy -0.19812 -0.4064) (xy -0.2032 -0.39624) (xy -0.20701 -0.38735) (xy -0.21209 -0.37719)
						(xy -0.2159 -0.36703) (xy -0.21844 -0.35687) (xy -0.22225 -0.34544) (xy -0.22352 -0.33528) (xy -0.22606 -0.32512)
						(xy -0.22733 -0.31369) (xy -0.22733 -0.30353) (xy -0.2286 -0.2921) (xy -0.22733 -0.28067) (xy -0.22733 -0.27051)
						(xy -0.22606 -0.25908) (xy -0.22352 -0.24892) (xy -0.22225 -0.23876) (xy -0.21844 -0.22733) (xy -0.2159 -0.21717)
						(xy -0.21209 -0.20701) (xy -0.20701 -0.19685) (xy -0.2032 -0.18796) (xy -0.19812 -0.1778) (xy -0.17272 -0.14224)
						(xy -0.1651 -0.13462) (xy -0.1651 0.7366) (xy -0.16256 0.76835) (xy -0.1524 0.8001) (xy -0.13716 0.82804)
						(xy -0.11684 0.85344) (xy -0.09144 0.87376) (xy -0.0635 0.889) (xy -0.03175 0.89916) (xy 0 0.9017)
						(xy 0.03175 0.89916) (xy 0.0635 0.889) (xy 0.09144 0.87376) (xy 0.11684 0.85344) (xy 0.13716 0.82804)
						(xy 0.1524 0.8001) (xy 0.16256 0.76835) (xy 0.1651 0.7366) (xy 0.1651 -0.13462) (xy 0.17272 -0.14224)
						(xy 0.19812 -0.1778) (xy 0.2032 -0.18796) (xy 0.20701 -0.19685) (xy 0.21209 -0.20701) (xy 0.2159 -0.21717)
						(xy 0.21844 -0.22733) (xy 0.22225 -0.23876) (xy 0.22352 -0.24892) (xy 0.22606 -0.25908) (xy 0.22733 -0.27051)
						(xy 0.22733 -0.28067) (xy 0.2286 -0.2921) (xy 0.22733 -0.30353) (xy 0.22733 -0.31369) (xy 0.22606 -0.32512)
						(xy 0.22352 -0.33528) (xy 0.22225 -0.34544) (xy 0.21844 -0.35687) (xy 0.2159 -0.36703) (xy 0.21209 -0.37719)
						(xy 0.20701 -0.38735) (xy 0.2032 -0.39624) (xy 0.19812 -0.4064) (xy 0.17272 -0.44196) (xy 0.1651 -0.44958)
						(xy 0.1651 -0.7366) (xy 0.16256 -0.76835) (xy 0.1524 -0.8001) (xy 0.13716 -0.82804) (xy 0.11684 -0.85344)
						(xy 0.09144 -0.87376) (xy 0.0635 -0.889) (xy 0.03175 -0.89916)
					)
					(width 0)
					(fill yes)
				)
			)
		)
	)
)
